(kicad_pcb
	(version 20260206)
	(generator "pcbnew")
	(generator_version "10.0")
	(general
		(thickness 1.6)
		(legacy_teardrops no)
	)
	(paper "A4")
	(title_block
		(title "04192023_DAF0TMB3IC0_F0TG_MB_C_brd_V02_OCP.brd")
		(comment 1 "Grand Teton / footprint 3955 of 8354 (U25), pads 5338-5447 of 6102")
	)
	(layers
		(0 "F.Cu" signal "TOP")
		(4 "In1.Cu" signal "GND")
		(6 "In2.Cu" signal "IN1")
		(8 "In3.Cu" signal "GND1")
		(10 "In4.Cu" signal "IN2")
		(12 "In5.Cu" signal "GND2")
		(14 "In6.Cu" signal "IN3")
		(16 "In7.Cu" signal "GND3")
		(18 "In8.Cu" signal "VCC")
		(20 "In9.Cu" signal "VCC1")
		(22 "In10.Cu" signal "GND4")
		(24 "In11.Cu" signal "IN4")
		(26 "In12.Cu" signal "GND5")
		(28 "In13.Cu" signal "IN5")
		(30 "In14.Cu" signal "GND6")
		(32 "In15.Cu" signal "IN6")
		(34 "In16.Cu" signal "GND7")
		(2 "B.Cu" signal "BOTTOM")
		(9 "F.Adhes" user "F.Adhesive")
		(11 "B.Adhes" user "B.Adhesive")
		(13 "F.Paste" user "Package Geometry/Pastemask Top")
		(15 "B.Paste" user "Package Geometry/Pastemask Bottom")
		(5 "F.SilkS" user "Ref Des/Silkscreen Top")
		(7 "B.SilkS" user "Ref Des/Silkscreen Bottom")
		(1 "F.Mask" user "Board Geometry/Soldermask Top")
		(3 "B.Mask" user "Board Geometry/Soldermask Bottom")
		(17 "Dwgs.User" user "User.Drawings")
		(19 "Cmts.User" user "User.Comments")
		(21 "Eco1.User" user "User.Eco1")
		(23 "Eco2.User" user "User.Eco2")
		(25 "Edge.Cuts" user "Board Geometry/Outline")
		(27 "Margin" user)
		(31 "F.CrtYd" user "Package Geometry/Place Bound Top")
		(29 "B.CrtYd" user "Package Geometry/Place Bound Bottom")
		(35 "F.Fab" user "Ref Des/Assembly Top")
		(33 "B.Fab" user "Ref Des/Assembly Bottom")
	)
	(footprint ""
		(layer "F.Cu")
		(at 359.867962 -258.880102 180)
		(property "Reference" "U25"
			(at -45.78477 -62.086744 0)
			(unlocked yes)
			(layer "F.SilkS")
			(effects
				(font
					(size 0.7874 0.5842)
					(thickness 0.1524)
				)
			)
		)
		(property "Value" ""
			(at 0 0 180)
			(layer "F.Fab")
			(effects
				(font
					(size 1.27 1.27)
				)
			)
		)
		(duplicate_pad_numbers_are_jumpers no)
		(pad "K29" smd circle
			(at -8.310118 -29.51988 180)
			(size 0.450088 0.450088)
			(layers "F.Cu" "F.Mask" "F.Paste")
			(net "GND")
		)
		(pad "K30" smd circle
			(at -7.370064 -29.51988 180)
			(size 0.450088 0.450088)
			(layers "F.Cu" "F.Mask" "F.Paste")
			(net "GND")
		)
		(pad "K31" smd circle
			(at -6.43001 -29.51988 180)
			(size 0.450088 0.450088)
			(layers "F.Cu" "F.Mask" "F.Paste")
			(net "GND")
		)
		(pad "K32" smd circle
			(at -5.489956 -29.51988 180)
			(size 0.450088 0.450088)
			(layers "F.Cu" "F.Mask" "F.Paste")
			(net "GND")
		)
		(pad "K33" smd circle
			(at -4.549902 -29.51988 180)
			(size 0.450088 0.450088)
			(layers "F.Cu" "F.Mask" "F.Paste")
			(net "GND")
		)
		(pad "K34" smd circle
			(at -3.610102 -29.51988 180)
			(size 0.450088 0.450088)
			(layers "F.Cu" "F.Mask" "F.Paste")
			(net "GND")
		)
		(pad "K35" smd circle
			(at -2.670048 -29.51988 180)
			(size 0.450088 0.450088)
			(layers "F.Cu" "F.Mask" "F.Paste")
			(net "GMI_CPU0_G2_CPU1_G0_TX_DP<14>")
		)
		(pad "K36" smd circle
			(at -1.729994 -29.51988 180)
			(size 0.450088 0.450088)
			(layers "F.Cu" "F.Mask" "F.Paste")
			(net "GMI_CPU0_G2_CPU1_G0_TX_DN<14>")
		)
		(pad "K37" smd circle
			(at -0.78994 -29.51988 180)
			(size 0.450088 0.450088)
			(layers "F.Cu" "F.Mask" "F.Paste")
			(net "GND")
		)
		(pad "K39" smd circle
			(at 1.089914 -29.51988 180)
			(size 0.450088 0.450088)
			(layers "F.Cu" "F.Mask" "F.Paste")
			(net "GND")
		)
		(pad "K40" smd circle
			(at 2.029968 -29.51988 180)
			(size 0.450088 0.450088)
			(layers "F.Cu" "F.Mask" "F.Paste")
			(net "GMI_CPU1_G2_CPU0_G0_TX_DN<1>")
		)
		(pad "K41" smd circle
			(at 2.970022 -29.51988 180)
			(size 0.450088 0.450088)
			(layers "F.Cu" "F.Mask" "F.Paste")
			(net "GMI_CPU1_G2_CPU0_G0_TX_DP<1>")
		)
		(pad "K42" smd circle
			(at 3.910076 -29.51988 180)
			(size 0.450088 0.450088)
			(layers "F.Cu" "F.Mask" "F.Paste")
			(net "GND")
		)
		(pad "K43" smd circle
			(at 4.849876 -29.51988 180)
			(size 0.450088 0.450088)
			(layers "F.Cu" "F.Mask" "F.Paste")
			(net "GND")
		)
		(pad "K44" smd circle
			(at 5.78993 -29.51988 180)
			(size 0.450088 0.450088)
			(layers "F.Cu" "F.Mask" "F.Paste")
			(net "GND")
		)
		(pad "K45" smd circle
			(at 6.729984 -29.51988 180)
			(size 0.450088 0.450088)
			(layers "F.Cu" "F.Mask" "F.Paste")
			(net "GND")
		)
		(pad "K46" smd circle
			(at 7.670038 -29.51988 180)
			(size 0.450088 0.450088)
			(layers "F.Cu" "F.Mask" "F.Paste")
			(net "GND")
		)
		(pad "K47" smd circle
			(at 8.610092 -29.51988 180)
			(size 0.450088 0.450088)
			(layers "F.Cu" "F.Mask" "F.Paste")
			(net "GND")
		)
		(pad "K48" smd circle
			(at 9.549892 -29.51988 180)
			(size 0.450088 0.450088)
			(layers "F.Cu" "F.Mask" "F.Paste")
			(net "GND")
		)
		(pad "K49" smd circle
			(at 10.489946 -29.51988 180)
			(size 0.450088 0.450088)
			(layers "F.Cu" "F.Mask" "F.Paste")
			(net "GND")
		)
		(pad "K50" smd circle
			(at 11.43 -29.51988 180)
			(size 0.450088 0.450088)
			(layers "F.Cu" "F.Mask" "F.Paste")
			(net "GND")
		)
		(pad "K51" smd circle
			(at 12.370054 -29.51988 180)
			(size 0.450088 0.450088)
			(layers "F.Cu" "F.Mask" "F.Paste")
			(net "GND")
		)
		(pad "K52" smd circle
			(at 13.310108 -29.51988 180)
			(size 0.450088 0.450088)
			(layers "F.Cu" "F.Mask" "F.Paste")
			(net "GND")
		)
		(pad "K53" smd circle
			(at 14.249908 -29.51988 180)
			(size 0.450088 0.450088)
			(layers "F.Cu" "F.Mask" "F.Paste")
			(net "GND")
		)
		(pad "K54" smd circle
			(at 15.189962 -29.51988 180)
			(size 0.450088 0.450088)
			(layers "F.Cu" "F.Mask" "F.Paste")
			(net "PVDDIO_P0")
		)
		(pad "K55" smd circle
			(at 16.130016 -29.51988 180)
			(size 0.450088 0.450088)
			(layers "F.Cu" "F.Mask" "F.Paste")
			(net "M_C_CPU0_SA_DQ<5>")
		)
		(pad "K56" smd circle
			(at 17.07007 -29.51988 180)
			(size 0.450088 0.450088)
			(layers "F.Cu" "F.Mask" "F.Paste")
			(net "M_C_CPU0_SA_DQ<6>")
		)
		(pad "K57" smd circle
			(at 18.010124 -29.51988 180)
			(size 0.450088 0.450088)
			(layers "F.Cu" "F.Mask" "F.Paste")
			(net "GND")
		)
		(pad "K58" smd circle
			(at 18.949924 -29.51988 180)
			(size 0.450088 0.450088)
			(layers "F.Cu" "F.Mask" "F.Paste")
			(net "M_D_CPU0_SA_DQ<5>")
		)
		(pad "K59" smd circle
			(at 19.889978 -29.51988 180)
			(size 0.450088 0.450088)
			(layers "F.Cu" "F.Mask" "F.Paste")
			(net "GND")
		)
		(pad "K60" smd circle
			(at 20.830032 -29.51988 180)
			(size 0.450088 0.450088)
			(layers "F.Cu" "F.Mask" "F.Paste")
			(net "M_D_CPU0_SA_DQ<6>")
		)
		(pad "K61" smd circle
			(at 21.770086 -29.51988 180)
			(size 0.450088 0.450088)
			(layers "F.Cu" "F.Mask" "F.Paste")
			(net "GND")
		)
		(pad "K62" smd circle
			(at 22.709886 -29.51988 180)
			(size 0.450088 0.450088)
			(layers "F.Cu" "F.Mask" "F.Paste")
			(net "M_B_CPU0_SA_DQ<5>")
		)
		(pad "K63" smd circle
			(at 23.64994 -29.51988 180)
			(size 0.450088 0.450088)
			(layers "F.Cu" "F.Mask" "F.Paste")
			(net "M_B_CPU0_SA_DQ<6>")
		)
		(pad "K64" smd circle
			(at 24.589994 -29.51988 180)
			(size 0.450088 0.450088)
			(layers "F.Cu" "F.Mask" "F.Paste")
			(net "GND")
		)
		(pad "K65" smd circle
			(at 25.530048 -29.51988 180)
			(size 0.450088 0.450088)
			(layers "F.Cu" "F.Mask" "F.Paste")
			(net "M_F_CPU0_SA_DQ<5>")
		)
		(pad "K66" smd circle
			(at 26.470102 -29.51988 180)
			(size 0.450088 0.450088)
			(layers "F.Cu" "F.Mask" "F.Paste")
			(net "GND")
		)
		(pad "K67" smd circle
			(at 27.409902 -29.51988 180)
			(size 0.450088 0.450088)
			(layers "F.Cu" "F.Mask" "F.Paste")
			(net "M_F_CPU0_SA_DQ<6>")
		)
		(pad "K68" smd circle
			(at 28.349956 -29.51988 180)
			(size 0.450088 0.450088)
			(layers "F.Cu" "F.Mask" "F.Paste")
			(net "GND")
		)
		(pad "K69" smd circle
			(at 29.29001 -29.51988 180)
			(size 0.450088 0.450088)
			(layers "F.Cu" "F.Mask" "F.Paste")
			(net "M_E_CPU0_SA_DQ<5>")
		)
		(pad "K70" smd circle
			(at 30.230064 -29.51988 180)
			(size 0.450088 0.450088)
			(layers "F.Cu" "F.Mask" "F.Paste")
			(net "M_E_CPU0_SA_DQ<6>")
		)
		(pad "K71" smd circle
			(at 31.170118 -29.51988 180)
			(size 0.450088 0.450088)
			(layers "F.Cu" "F.Mask" "F.Paste")
			(net "GND")
		)
		(pad "K72" smd circle
			(at 32.109918 -29.51988 180)
			(size 0.450088 0.450088)
			(layers "F.Cu" "F.Mask" "F.Paste")
			(net "M_A_CPU0_SA_DQ<5>")
		)
		(pad "K73" smd circle
			(at 33.049972 -29.51988 180)
			(size 0.450088 0.450088)
			(layers "F.Cu" "F.Mask" "F.Paste")
			(net "GND")
		)
		(pad "K74" smd circle
			(at 33.990026 -29.51988 180)
			(size 0.450088 0.450088)
			(layers "F.Cu" "F.Mask" "F.Paste")
			(net "M_A_CPU0_SA_DQ<6>")
		)
		(pad "L1" smd circle
			(at -34.159952 -28.710128 180)
			(size 0.450088 0.450088)
			(layers "F.Cu" "F.Mask" "F.Paste")
			(net "GND")
		)
		(pad "L2" smd circle
			(at -33.219898 -28.710128 180)
			(size 0.450088 0.450088)
			(layers "F.Cu" "F.Mask" "F.Paste")
			(net "M_G_CPU0_SA_DQ<8>")
		)
		(pad "L3" smd circle
			(at -32.280098 -28.710128 180)
			(size 0.450088 0.450088)
			(layers "F.Cu" "F.Mask" "F.Paste")
			(net "M_G_CPU0_SA_DQ<7>")
		)
		(pad "L4" smd circle
			(at -31.340044 -28.710128 180)
			(size 0.450088 0.450088)
			(layers "F.Cu" "F.Mask" "F.Paste")
			(net "PVDDCR_SOC_P0")
		)
		(pad "L5" smd circle
			(at -30.39999 -28.710128 180)
			(size 0.450088 0.450088)
			(layers "F.Cu" "F.Mask" "F.Paste")
			(net "M_K_CPU0_SA_DQ<8>")
		)
		(pad "L6" smd circle
			(at -29.459936 -28.710128 180)
			(size 0.450088 0.450088)
			(layers "F.Cu" "F.Mask" "F.Paste")
			(net "GND")
		)
		(pad "L7" smd circle
			(at -28.519882 -28.710128 180)
			(size 0.450088 0.450088)
			(layers "F.Cu" "F.Mask" "F.Paste")
			(net "M_K_CPU0_SA_DQ<7>")
		)
		(pad "L8" smd circle
			(at -27.580082 -28.710128 180)
			(size 0.450088 0.450088)
			(layers "F.Cu" "F.Mask" "F.Paste")
			(net "GND")
		)
		(pad "L9" smd circle
			(at -26.640028 -28.710128 180)
			(size 0.450088 0.450088)
			(layers "F.Cu" "F.Mask" "F.Paste")
			(net "M_L_CPU0_SA_DQ<8>")
		)
		(pad "L10" smd circle
			(at -25.699974 -28.710128 180)
			(size 0.450088 0.450088)
			(layers "F.Cu" "F.Mask" "F.Paste")
			(net "M_L_CPU0_SA_DQ<7>")
		)
		(pad "L11" smd circle
			(at -24.75992 -28.710128 180)
			(size 0.450088 0.450088)
			(layers "F.Cu" "F.Mask" "F.Paste")
			(net "PVDDCR_SOC_P0")
		)
		(pad "L12" smd circle
			(at -23.82012 -28.710128 180)
			(size 0.450088 0.450088)
			(layers "F.Cu" "F.Mask" "F.Paste")
			(net "M_H_CPU0_SA_DQ<8>")
		)
		(pad "L13" smd circle
			(at -22.880066 -28.710128 180)
			(size 0.450088 0.450088)
			(layers "F.Cu" "F.Mask" "F.Paste")
			(net "GND")
		)
		(pad "L14" smd circle
			(at -21.940012 -28.710128 180)
			(size 0.450088 0.450088)
			(layers "F.Cu" "F.Mask" "F.Paste")
			(net "M_H_CPU0_SA_DQ<7>")
		)
		(pad "L15" smd circle
			(at -20.999958 -28.710128 180)
			(size 0.450088 0.450088)
			(layers "F.Cu" "F.Mask" "F.Paste")
			(net "GND")
		)
		(pad "L16" smd circle
			(at -20.059904 -28.710128 180)
			(size 0.450088 0.450088)
			(layers "F.Cu" "F.Mask" "F.Paste")
			(net "M_J_CPU0_SA_DQ<8>")
		)
		(pad "L17" smd circle
			(at -19.120104 -28.710128 180)
			(size 0.450088 0.450088)
			(layers "F.Cu" "F.Mask" "F.Paste")
			(net "M_J_CPU0_SA_DQ<7>")
		)
		(pad "L18" smd circle
			(at -18.18005 -28.710128 180)
			(size 0.450088 0.450088)
			(layers "F.Cu" "F.Mask" "F.Paste")
			(net "PVDDCR_SOC_P0")
		)
		(pad "L19" smd circle
			(at -17.239996 -28.710128 180)
			(size 0.450088 0.450088)
			(layers "F.Cu" "F.Mask" "F.Paste")
			(net "M_I_CPU0_SA_DQ<8>")
		)
		(pad "L20" smd circle
			(at -16.299942 -28.710128 180)
			(size 0.450088 0.450088)
			(layers "F.Cu" "F.Mask" "F.Paste")
			(net "GND")
		)
		(pad "L21" smd circle
			(at -15.359888 -28.710128 180)
			(size 0.450088 0.450088)
			(layers "F.Cu" "F.Mask" "F.Paste")
			(net "M_I_CPU0_SA_DQ<7>")
		)
		(pad "L22" smd circle
			(at -14.420088 -28.710128 180)
			(size 0.450088 0.450088)
			(layers "F.Cu" "F.Mask" "F.Paste")
			(net "GND")
		)
		(pad "L23" smd circle
			(at -13.480034 -28.710128 180)
			(size 0.450088 0.450088)
			(layers "F.Cu" "F.Mask" "F.Paste")
			(net "GMI_CPU0_G2_CPU1_G0_TX_DP<3>")
		)
		(pad "L24" smd circle
			(at -12.53998 -28.710128 180)
			(size 0.450088 0.450088)
			(layers "F.Cu" "F.Mask" "F.Paste")
			(net "GMI_CPU0_G2_CPU1_G0_TX_DN<3>")
		)
		(pad "L25" smd circle
			(at -11.599926 -28.710128 180)
			(size 0.450088 0.450088)
			(layers "F.Cu" "F.Mask" "F.Paste")
			(net "GND")
		)
		(pad "L26" smd circle
			(at -10.659872 -28.710128 180)
			(size 0.450088 0.450088)
			(layers "F.Cu" "F.Mask" "F.Paste")
			(net "GMI_CPU0_G2_CPU1_G0_TX_DP<6>")
		)
		(pad "L27" smd circle
			(at -9.720072 -28.710128 180)
			(size 0.450088 0.450088)
			(layers "F.Cu" "F.Mask" "F.Paste")
			(net "GMI_CPU0_G2_CPU1_G0_TX_DN<6>")
		)
		(pad "L28" smd circle
			(at -8.780018 -28.710128 180)
			(size 0.450088 0.450088)
			(layers "F.Cu" "F.Mask" "F.Paste")
			(net "GND")
		)
		(pad "L29" smd circle
			(at -7.839964 -28.710128 180)
			(size 0.450088 0.450088)
			(layers "F.Cu" "F.Mask" "F.Paste")
			(net "GMI_CPU0_G2_CPU1_G0_TX_DP<9>")
		)
		(pad "L30" smd circle
			(at -6.89991 -28.710128 180)
			(size 0.450088 0.450088)
			(layers "F.Cu" "F.Mask" "F.Paste")
			(net "GMI_CPU0_G2_CPU1_G0_TX_DN<9>")
		)
		(pad "L31" smd circle
			(at -5.96011 -28.710128 180)
			(size 0.450088 0.450088)
			(layers "F.Cu" "F.Mask" "F.Paste")
			(net "GND")
		)
		(pad "L32" smd circle
			(at -5.020056 -28.710128 180)
			(size 0.450088 0.450088)
			(layers "F.Cu" "F.Mask" "F.Paste")
			(net "GMI_CPU0_G2_CPU1_G0_TX_DP<12>")
		)
		(pad "L33" smd circle
			(at -4.080002 -28.710128 180)
			(size 0.450088 0.450088)
			(layers "F.Cu" "F.Mask" "F.Paste")
			(net "GMI_CPU0_G2_CPU1_G0_TX_DN<12>")
		)
		(pad "L34" smd circle
			(at -3.139948 -28.710128 180)
			(size 0.450088 0.450088)
			(layers "F.Cu" "F.Mask" "F.Paste")
			(net "GND")
		)
		(pad "L35" smd circle
			(at -2.199894 -28.710128 180)
			(size 0.450088 0.450088)
			(layers "F.Cu" "F.Mask" "F.Paste")
			(net "GND")
		)
		(pad "L36" smd circle
			(at -1.260094 -28.710128 180)
			(size 0.450088 0.450088)
			(layers "F.Cu" "F.Mask" "F.Paste")
			(net "GND")
		)
		(pad "L40" smd circle
			(at 1.560068 -28.710128 180)
			(size 0.450088 0.450088)
			(layers "F.Cu" "F.Mask" "F.Paste")
			(net "GND")
		)
		(pad "L41" smd circle
			(at 2.500122 -28.710128 180)
			(size 0.450088 0.450088)
			(layers "F.Cu" "F.Mask" "F.Paste")
			(net "GND")
		)
		(pad "L42" smd circle
			(at 3.439922 -28.710128 180)
			(size 0.450088 0.450088)
			(layers "F.Cu" "F.Mask" "F.Paste")
			(net "GND")
		)
		(pad "L43" smd circle
			(at 4.379976 -28.710128 180)
			(size 0.450088 0.450088)
			(layers "F.Cu" "F.Mask" "F.Paste")
			(net "GMI_CPU1_G2_CPU0_G0_TX_DN<3>")
		)
		(pad "L44" smd circle
			(at 5.32003 -28.710128 180)
			(size 0.450088 0.450088)
			(layers "F.Cu" "F.Mask" "F.Paste")
			(net "GMI_CPU1_G2_CPU0_G0_TX_DP<3>")
		)
		(pad "L45" smd circle
			(at 6.260084 -28.710128 180)
			(size 0.450088 0.450088)
			(layers "F.Cu" "F.Mask" "F.Paste")
			(net "GND")
		)
		(pad "L46" smd circle
			(at 7.199884 -28.710128 180)
			(size 0.450088 0.450088)
			(layers "F.Cu" "F.Mask" "F.Paste")
			(net "GMI_CPU1_G2_CPU0_G0_TX_DN<6>")
		)
		(pad "L47" smd circle
			(at 8.139938 -28.710128 180)
			(size 0.450088 0.450088)
			(layers "F.Cu" "F.Mask" "F.Paste")
			(net "GMI_CPU1_G2_CPU0_G0_TX_DP<6>")
		)
		(pad "L48" smd circle
			(at 9.079992 -28.710128 180)
			(size 0.450088 0.450088)
			(layers "F.Cu" "F.Mask" "F.Paste")
			(net "GND")
		)
		(pad "L49" smd circle
			(at 10.020046 -28.710128 180)
			(size 0.450088 0.450088)
			(layers "F.Cu" "F.Mask" "F.Paste")
			(net "GMI_CPU1_G2_CPU0_G0_TX_DN<9>")
		)
		(pad "L50" smd circle
			(at 10.9601 -28.710128 180)
			(size 0.450088 0.450088)
			(layers "F.Cu" "F.Mask" "F.Paste")
			(net "GMI_CPU1_G2_CPU0_G0_TX_DP<9>")
		)
		(pad "L51" smd circle
			(at 11.8999 -28.710128 180)
			(size 0.450088 0.450088)
			(layers "F.Cu" "F.Mask" "F.Paste")
			(net "GND")
		)
		(pad "L52" smd circle
			(at 12.839954 -28.710128 180)
			(size 0.450088 0.450088)
			(layers "F.Cu" "F.Mask" "F.Paste")
			(net "GMI_CPU1_G2_CPU0_G0_TX_DN<12>")
		)
		(pad "L53" smd circle
			(at 13.780008 -28.710128 180)
			(size 0.450088 0.450088)
			(layers "F.Cu" "F.Mask" "F.Paste")
			(net "GMI_CPU1_G2_CPU0_G0_TX_DP<12>")
		)
		(pad "L54" smd circle
			(at 14.720062 -28.710128 180)
			(size 0.450088 0.450088)
			(layers "F.Cu" "F.Mask" "F.Paste")
			(net "GND")
		)
		(pad "L55" smd circle
			(at 15.660116 -28.710128 180)
			(size 0.450088 0.450088)
			(layers "F.Cu" "F.Mask" "F.Paste")
			(net "M_C_CPU0_SA_DQ<7>")
		)
		(pad "L56" smd circle
			(at 16.599916 -28.710128 180)
			(size 0.450088 0.450088)
			(layers "F.Cu" "F.Mask" "F.Paste")
			(net "GND")
		)
		(pad "L57" smd circle
			(at 17.53997 -28.710128 180)
			(size 0.450088 0.450088)
			(layers "F.Cu" "F.Mask" "F.Paste")
			(net "M_C_CPU0_SA_DQ<8>")
		)
		(pad "L58" smd circle
			(at 18.480024 -28.710128 180)
			(size 0.450088 0.450088)
			(layers "F.Cu" "F.Mask" "F.Paste")
			(net "PVDDIO_P0")
		)
		(pad "L59" smd circle
			(at 19.420078 -28.710128 180)
			(size 0.450088 0.450088)
			(layers "F.Cu" "F.Mask" "F.Paste")
			(net "M_D_CPU0_SA_DQ<7>")
		)
		(pad "L60" smd circle
			(at 20.359878 -28.710128 180)
			(size 0.450088 0.450088)
			(layers "F.Cu" "F.Mask" "F.Paste")
			(net "M_D_CPU0_SA_DQ<8>")
		)
		(pad "L61" smd circle
			(at 21.299932 -28.710128 180)
			(size 0.450088 0.450088)
			(layers "F.Cu" "F.Mask" "F.Paste")
			(net "GND")
		)
		(pad "L62" smd circle
			(at 22.239986 -28.710128 180)
			(size 0.450088 0.450088)
			(layers "F.Cu" "F.Mask" "F.Paste")
			(net "M_B_CPU0_SA_DQ<7>")
		)
		(pad "L63" smd circle
			(at 23.18004 -28.710128 180)
			(size 0.450088 0.450088)
			(layers "F.Cu" "F.Mask" "F.Paste")
			(net "GND")
		)
		(pad "L64" smd circle
			(at 24.120094 -28.710128 180)
			(size 0.450088 0.450088)
			(layers "F.Cu" "F.Mask" "F.Paste")
			(net "M_B_CPU0_SA_DQ<8>")
		)
		(pad "L65" smd circle
			(at 25.059894 -28.710128 180)
			(size 0.450088 0.450088)
			(layers "F.Cu" "F.Mask" "F.Paste")
			(net "PVDDIO_P0")
		)
		(pad "L66" smd circle
			(at 25.999948 -28.710128 180)
			(size 0.450088 0.450088)
			(layers "F.Cu" "F.Mask" "F.Paste")
			(net "M_F_CPU0_SA_DQ<7>")
		)
		(pad "L67" smd circle
			(at 26.940002 -28.710128 180)
			(size 0.450088 0.450088)
			(layers "F.Cu" "F.Mask" "F.Paste")
			(net "M_F_CPU0_SA_DQ<8>")
		)
		(pad "L68" smd circle
			(at 27.880056 -28.710128 180)
			(size 0.450088 0.450088)
			(layers "F.Cu" "F.Mask" "F.Paste")
			(net "GND")
		)
	)
)
